FILE_TYPE = MACRO_DRAWING;
SET COLOR_WIRE YELLOW;
SET COLOR_PROP ORANGE;
SET COLOR_DOT WHITE;
SET COLOR_ARC YELLOW;
SET COLOR_BODY GREEN;
SET COLOR_NOTE PURPLE;
SET PROP_DISPLAY VALUE;
SET PAGE_NUMBER P414;
FORCEADD QUANTA_TITLE_BLOCK_C..1
(0 0);
FORCEPROP 1 LAST CUSTOM_TXT_CDS <NAME_2>
J 0
(-3175 50);
FORCEPROP 1 LAST CUSTOM_TXT_CDS <NAME_1>
J 0
(-3175 175);
FORCEPROP 1 LAST CUSTOM_TXT_CDS <Q_NUMBER>
J 0
(-1403 103);
DISPLAY 1.212766 (-1403 103);
FORCEPROP 1 LAST CUSTOM_TXT_CDS <Q_PROJ>
J 0
(-2382 102);
DISPLAY 1.212766 (-2382 102);
FORCEPROP 1 LAST CUSTOM_TXT_CDS <Q_REV>
J 0
(-184 103);
DISPLAY 1.212766 (-184 103);
FORCEPROP 1 LAST CUSTOM_TXT_CDS <CON_LAST_MODIFIED>
J 0
(-1885 15);
DISPLAY 0.978723 (-1885 15);
FORCEPROP 1 LAST CUSTOM_TXT_CDS <CON_PAGE_NUM> OF <CON_TOTAL_PAGES>
J 0
(-446 18);
DISPLAY 0.978723 (-446 18);
FORCEPROP 1 LAST Q_TITLE BLANK
J 0
(-9366 26);
DISPLAY 2.446809 (-9366 26);
PAINT GREEN (-9366 26);
FORCEPROP 2 LAST CDS_LIB pure_quanta
J 0
(0 0);
DISPLAY INVISIBLE (0 0);
FORCEPROP 1 LAST CDS_LMAN_SYM_OUTLINE -9475,6775,100,-125
J 0
(0 0);
DISPLAY 0.468085 (0 0);
PAINT GREEN (0 0);
DISPLAY INVISIBLE (0 0);
FORCEPROP 2 LAST PAGE_BORDER TRUE
J 0
(-7890 5250);
DISPLAY 0.638298 (-7890 5250);
PAINT PINK (-7890 5250);
DISPLAY INVISIBLE (-7890 5250);
FORCEPROP 2 LAST CDS_XR_PAGE_TITLE CR-294 : @T6G_MB_LIB.T6G(SCH_1):PAGE294
J 0
(-7890 5250);
DISPLAY 0.638298 (-7890 5250);
PAINT PINK (-7890 5250);
DISPLAY INVISIBLE (-7890 5250);
FORCEPROP 2 LAST CUSTOM_TXT_CDS <XR_PAGE_TITLE>
J 0
(-7890 5250);
DISPLAY 0.638298 (-7890 5250);
PAINT PINK (-7890 5250);
DISPLAY INVISIBLE (-7890 5250);
FORCEPROP 1 LAST COMMENT_BODY TRUE
J 0
(12 -13);
DISPLAY 0.978723 (12 -13);
PAINT GREEN (12 -13);
DISPLAY INVISIBLE (12 -13);
FORCEPROP 1 LAST Q_DEPT BU9
J 1
(-3763 49);
DISPLAY 1.957447 (-3763 49);
PAINT GREEN (-3763 49);
DISPLAY INVISIBLE (-3763 49);
FORCEPROP 0 LAST CDS_CON_LAST_MODIFIED Thu Aug 24 10:16:19 2023
J 0
(-1885 15);
DISPLAY INVISIBLE (-1885 15);
QUIT
